(kicad_pcb
	(version 20260206)
	(generator "pcbnew")
	(generator_version "10.0")
	(general
		(thickness 1.6)
		(legacy_teardrops no)
	)
	(paper "A4")
	(title_block
		(title "04192023_DAF0TMB3IC0_F0TG_MB_C_brd_V02_OCP.brd")
		(comment 1 "Grand Teton / footprint 2783 of 8354 (U26), pads 4789-4900 of 6102")
	)
	(layers
		(0 "F.Cu" signal "TOP")
		(4 "In1.Cu" signal "GND")
		(6 "In2.Cu" signal "IN1")
		(8 "In3.Cu" signal "GND1")
		(10 "In4.Cu" signal "IN2")
		(12 "In5.Cu" signal "GND2")
		(14 "In6.Cu" signal "IN3")
		(16 "In7.Cu" signal "GND3")
		(18 "In8.Cu" signal "VCC")
		(20 "In9.Cu" signal "VCC1")
		(22 "In10.Cu" signal "GND4")
		(24 "In11.Cu" signal "IN4")
		(26 "In12.Cu" signal "GND5")
		(28 "In13.Cu" signal "IN5")
		(30 "In14.Cu" signal "GND6")
		(32 "In15.Cu" signal "IN6")
		(34 "In16.Cu" signal "GND7")
		(2 "B.Cu" signal "BOTTOM")
		(9 "F.Adhes" user "F.Adhesive")
		(11 "B.Adhes" user "B.Adhesive")
		(13 "F.Paste" user "Package Geometry/Pastemask Top")
		(15 "B.Paste" user "Package Geometry/Pastemask Bottom")
		(5 "F.SilkS" user "Ref Des/Silkscreen Top")
		(7 "B.SilkS" user "Ref Des/Silkscreen Bottom")
		(1 "F.Mask" user "Board Geometry/Soldermask Top")
		(3 "B.Mask" user "Board Geometry/Soldermask Bottom")
		(17 "Dwgs.User" user "User.Drawings")
		(19 "Cmts.User" user "User.Comments")
		(21 "Eco1.User" user "User.Eco1")
		(23 "Eco2.User" user "User.Eco2")
		(25 "Edge.Cuts" user "Board Geometry/Outline")
		(27 "Margin" user)
		(31 "F.CrtYd" user "Package Geometry/Place Bound Top")
		(29 "B.CrtYd" user "Package Geometry/Place Bound Bottom")
		(35 "F.Fab" user "Ref Des/Assembly Top")
		(33 "B.Fab" user "Ref Des/Assembly Bottom")
	)
	(footprint ""
		(layer "F.Cu")
		(at 111.927894 -258.880356 180)
		(property "Reference" "U26"
			(at -45.05579 -61.794136 0)
			(unlocked yes)
			(layer "F.SilkS")
			(effects
				(font
					(size 0.7874 0.5842)
					(thickness 0.1524)
				)
			)
		)
		(property "Value" ""
			(at 0 0 180)
			(layer "F.Fab")
			(effects
				(font
					(size 1.27 1.27)
				)
			)
		)
		(duplicate_pad_numbers_are_jumpers no)
		(pad "DG40" smd circle
			(at 1.260094 35.189922 180)
			(size 0.450088 0.450088)
			(layers "F.Cu" "F.Mask" "F.Paste")
			(net "NC_CPU1_USB10_OC_N")
		)
		(pad "DG41" smd circle
			(at 2.199894 35.189922 180)
			(size 0.450088 0.450088)
			(layers "F.Cu" "F.Mask" "F.Paste")
			(net "GND")
		)
		(pad "DG42" smd circle
			(at 3.139948 35.189922 180)
			(size 0.450088 0.450088)
			(layers "F.Cu" "F.Mask" "F.Paste")
			(net "Net_2175")
		)
		(pad "DG43" smd circle
			(at 4.080002 35.189922 180)
			(size 0.450088 0.450088)
			(layers "F.Cu" "F.Mask" "F.Paste")
			(net "GND")
		)
		(pad "DG44" smd circle
			(at 5.020056 35.189922 180)
			(size 0.450088 0.450088)
			(layers "F.Cu" "F.Mask" "F.Paste")
			(net "P3E_CPU1_P4_RX_DN<3>")
		)
		(pad "DG45" smd circle
			(at 5.96011 35.189922 180)
			(size 0.450088 0.450088)
			(layers "F.Cu" "F.Mask" "F.Paste")
			(net "P3E_CPU1_P4_RX_DP<3>")
		)
		(pad "DG46" smd circle
			(at 6.89991 35.189922 180)
			(size 0.450088 0.450088)
			(layers "F.Cu" "F.Mask" "F.Paste")
			(net "GND")
		)
		(pad "DG47" smd circle
			(at 7.839964 35.189922 180)
			(size 0.450088 0.450088)
			(layers "F.Cu" "F.Mask" "F.Paste")
			(net "P3E_CPU1_P4_RX_DN<2>")
		)
		(pad "DG48" smd circle
			(at 8.780018 35.189922 180)
			(size 0.450088 0.450088)
			(layers "F.Cu" "F.Mask" "F.Paste")
			(net "P3E_CPU1_P4_RX_DP<2>")
		)
		(pad "DG49" smd circle
			(at 9.720072 35.189922 180)
			(size 0.450088 0.450088)
			(layers "F.Cu" "F.Mask" "F.Paste")
			(net "GND")
		)
		(pad "DG50" smd circle
			(at 10.659872 35.189922 180)
			(size 0.450088 0.450088)
			(layers "F.Cu" "F.Mask" "F.Paste")
			(net "P3E_CPU1_P4_RX_DN<1>")
		)
		(pad "DG51" smd circle
			(at 11.599926 35.189922 180)
			(size 0.450088 0.450088)
			(layers "F.Cu" "F.Mask" "F.Paste")
			(net "P3E_CPU1_P4_RX_DP<1>")
		)
		(pad "DG52" smd circle
			(at 12.53998 35.189922 180)
			(size 0.450088 0.450088)
			(layers "F.Cu" "F.Mask" "F.Paste")
			(net "GND")
		)
		(pad "DG53" smd circle
			(at 13.480034 35.189922 180)
			(size 0.450088 0.450088)
			(layers "F.Cu" "F.Mask" "F.Paste")
			(net "P3E_CPU1_P4_RX_DN<0>")
		)
		(pad "DG54" smd circle
			(at 14.420088 35.189922 180)
			(size 0.450088 0.450088)
			(layers "F.Cu" "F.Mask" "F.Paste")
			(net "P3E_CPU1_P4_RX_DP<0>")
		)
		(pad "DG55" smd circle
			(at 15.359888 35.189922 180)
			(size 0.450088 0.450088)
			(layers "F.Cu" "F.Mask" "F.Paste")
			(net "GND")
		)
		(pad "DG56" smd circle
			(at 16.299942 35.189922 180)
			(size 0.450088 0.450088)
			(layers "F.Cu" "F.Mask" "F.Paste")
			(net "GND")
		)
		(pad "DG57" smd circle
			(at 17.239996 35.189922 180)
			(size 0.450088 0.450088)
			(layers "F.Cu" "F.Mask" "F.Paste")
			(net "PVDDCR_CPU1_P1")
		)
		(pad "DG58" smd circle
			(at 18.18005 35.189922 180)
			(size 0.450088 0.450088)
			(layers "F.Cu" "F.Mask" "F.Paste")
			(net "NC_CPU1_USB3_USB11_TXP")
		)
		(pad "DG59" smd circle
			(at 19.120104 35.189922 180)
			(size 0.450088 0.450088)
			(layers "F.Cu" "F.Mask" "F.Paste")
			(net "GND")
		)
		(pad "DG60" smd circle
			(at 20.059904 35.189922 180)
			(size 0.450088 0.450088)
			(layers "F.Cu" "F.Mask" "F.Paste")
			(net "GND")
		)
		(pad "DG61" smd circle
			(at 20.999958 35.189922 180)
			(size 0.450088 0.450088)
			(layers "F.Cu" "F.Mask" "F.Paste")
			(net "GND")
		)
		(pad "DG62" smd circle
			(at 21.940012 35.189922 180)
			(size 0.450088 0.450088)
			(layers "F.Cu" "F.Mask" "F.Paste")
			(net "GND")
		)
		(pad "DG63" smd circle
			(at 22.880066 35.189922 180)
			(size 0.450088 0.450088)
			(layers "F.Cu" "F.Mask" "F.Paste")
			(net "GND")
		)
		(pad "DG64" smd circle
			(at 23.82012 35.189922 180)
			(size 0.450088 0.450088)
			(layers "F.Cu" "F.Mask" "F.Paste")
			(net "PVDDIO_P1")
		)
		(pad "DG65" smd circle
			(at 24.75992 35.189922 180)
			(size 0.450088 0.450088)
			(layers "F.Cu" "F.Mask" "F.Paste")
			(net "GND")
		)
		(pad "DG66" smd circle
			(at 25.699974 35.189922 180)
			(size 0.450088 0.450088)
			(layers "F.Cu" "F.Mask" "F.Paste")
			(net "GND")
		)
		(pad "DG67" smd circle
			(at 26.640028 35.189922 180)
			(size 0.450088 0.450088)
			(layers "F.Cu" "F.Mask" "F.Paste")
			(net "GND")
		)
		(pad "DG68" smd circle
			(at 27.580082 35.189922 180)
			(size 0.450088 0.450088)
			(layers "F.Cu" "F.Mask" "F.Paste")
			(net "GND")
		)
		(pad "DG69" smd circle
			(at 28.519882 35.189922 180)
			(size 0.450088 0.450088)
			(layers "F.Cu" "F.Mask" "F.Paste")
			(net "GND")
		)
		(pad "DG70" smd circle
			(at 29.459936 35.189922 180)
			(size 0.450088 0.450088)
			(layers "F.Cu" "F.Mask" "F.Paste")
			(net "GND")
		)
		(pad "DG71" smd circle
			(at 30.39999 35.189922 180)
			(size 0.450088 0.450088)
			(layers "F.Cu" "F.Mask" "F.Paste")
			(net "PVDDIO_P1")
		)
		(pad "DG72" smd circle
			(at 31.340044 35.189922 180)
			(size 0.450088 0.450088)
			(layers "F.Cu" "F.Mask" "F.Paste")
			(net "FM_P1_PCC1_N")
		)
		(pad "DG73" smd circle
			(at 32.280098 35.189922 180)
			(size 0.450088 0.450088)
			(layers "F.Cu" "F.Mask" "F.Paste")
			(net "SVID_PVDDCR_CPU1_P1_SVTO")
		)
		(pad "DG74" smd circle
			(at 33.219898 35.189922 180)
			(size 0.450088 0.450088)
			(layers "F.Cu" "F.Mask" "F.Paste")
			(net "GND")
		)
		(pad "DG75" smd circle
			(at 34.159952 35.189922 180)
			(size 0.450088 0.450088)
			(layers "F.Cu" "F.Mask" "F.Paste")
			(net "GND")
		)
		(pad "DH3" smd circle
			(at -33.049972 35.999928 180)
			(size 0.450088 0.450088)
			(layers "F.Cu" "F.Mask" "F.Paste")
			(net "VSENSE_PVDD11_S3_P1_DP")
		)
		(pad "DH4" smd circle
			(at -32.109918 35.999928 180)
			(size 0.450088 0.450088)
			(layers "F.Cu" "F.Mask" "F.Paste")
			(net "Net_2085")
		)
		(pad "DH5" smd circle
			(at -31.170118 35.999928 180)
			(size 0.450088 0.450088)
			(layers "F.Cu" "F.Mask" "F.Paste")
			(net "GND")
		)
		(pad "DH6" smd circle
			(at -30.230064 35.999928 180)
			(size 0.450088 0.450088)
			(layers "F.Cu" "F.Mask" "F.Paste")
			(net "RST_CPU1_SYS_N")
		)
		(pad "DH7" smd circle
			(at -29.29001 35.999928 180)
			(size 0.450088 0.450088)
			(layers "F.Cu" "F.Mask" "F.Paste")
			(net "NC_CPU1_PWR_BTN_N")
		)
		(pad "DH8" smd circle
			(at -28.349956 35.999928 180)
			(size 0.450088 0.450088)
			(layers "F.Cu" "F.Mask" "F.Paste")
			(net "GND")
		)
		(pad "DH9" smd circle
			(at -27.409902 35.999928 180)
			(size 0.450088 0.450088)
			(layers "F.Cu" "F.Mask" "F.Paste")
			(net "CLK_CPU1_RTCCLK")
		)
		(pad "DH10" smd circle
			(at -26.470102 35.999928 180)
			(size 0.450088 0.450088)
			(layers "F.Cu" "F.Mask" "F.Paste")
			(net "CPU1_SP5R4")
		)
		(pad "DH11" smd circle
			(at -25.530048 35.999928 180)
			(size 0.450088 0.450088)
			(layers "F.Cu" "F.Mask" "F.Paste")
			(net "GND")
		)
		(pad "DH12" smd circle
			(at -24.589994 35.999928 180)
			(size 0.450088 0.450088)
			(layers "F.Cu" "F.Mask" "F.Paste")
			(net "Net_2093")
		)
		(pad "DH13" smd circle
			(at -23.64994 35.999928 180)
			(size 0.450088 0.450088)
			(layers "F.Cu" "F.Mask" "F.Paste")
			(net "Net_2170")
		)
		(pad "DH14" smd circle
			(at -22.709886 35.999928 180)
			(size 0.450088 0.450088)
			(layers "F.Cu" "F.Mask" "F.Paste")
			(net "Net_2174")
		)
		(pad "DH15" smd circle
			(at -21.770086 35.999928 180)
			(size 0.450088 0.450088)
			(layers "F.Cu" "F.Mask" "F.Paste")
			(net "FM_CPU1_BMC_RST_N")
		)
		(pad "DH16" smd circle
			(at -20.830032 35.999928 180)
			(size 0.450088 0.450088)
			(layers "F.Cu" "F.Mask" "F.Paste")
			(net "FM_BMC_TPM_PRES_N")
		)
		(pad "DH17" smd circle
			(at -19.889978 35.999928 180)
			(size 0.450088 0.450088)
			(layers "F.Cu" "F.Mask" "F.Paste")
			(net "Net_2164")
		)
		(pad "DH18" smd circle
			(at -18.949924 35.999928 180)
			(size 0.450088 0.450088)
			(layers "F.Cu" "F.Mask" "F.Paste")
			(net "GND")
		)
		(pad "DH19" smd circle
			(at -18.010124 35.999928 180)
			(size 0.450088 0.450088)
			(layers "F.Cu" "F.Mask" "F.Paste")
			(net "PVDDCR_CPU1_P1")
		)
		(pad "DH20" smd circle
			(at -17.07007 35.999928 180)
			(size 0.450088 0.450088)
			(layers "F.Cu" "F.Mask" "F.Paste")
			(net "PVDDCR_CPU1_P1")
		)
		(pad "DH21" smd circle
			(at -16.130016 35.999928 180)
			(size 0.450088 0.450088)
			(layers "F.Cu" "F.Mask" "F.Paste")
			(net "Net_2165")
		)
		(pad "DH22" smd circle
			(at -15.189962 35.999928 180)
			(size 0.450088 0.450088)
			(layers "F.Cu" "F.Mask" "F.Paste")
			(net "PVDDCR_CPU1_P1")
		)
		(pad "DH23" smd circle
			(at -14.249908 35.999928 180)
			(size 0.450088 0.450088)
			(layers "F.Cu" "F.Mask" "F.Paste")
			(net "PVDDCR_CPU1_P1")
		)
		(pad "DH24" smd circle
			(at -13.310108 35.999928 180)
			(size 0.450088 0.450088)
			(layers "F.Cu" "F.Mask" "F.Paste")
			(net "Net_2109")
		)
		(pad "DH25" smd circle
			(at -12.370054 35.999928 180)
			(size 0.450088 0.450088)
			(layers "F.Cu" "F.Mask" "F.Paste")
			(net "PVDDCR_CPU1_P1")
		)
		(pad "DH26" smd circle
			(at -11.43 35.999928 180)
			(size 0.450088 0.450088)
			(layers "F.Cu" "F.Mask" "F.Paste")
			(net "PVDDCR_CPU1_P1")
		)
		(pad "DH27" smd circle
			(at -10.489946 35.999928 180)
			(size 0.450088 0.450088)
			(layers "F.Cu" "F.Mask" "F.Paste")
			(net "Net_2120")
		)
		(pad "DH28" smd circle
			(at -9.549892 35.999928 180)
			(size 0.450088 0.450088)
			(layers "F.Cu" "F.Mask" "F.Paste")
			(net "PVDDCR_CPU1_P1")
		)
		(pad "DH29" smd circle
			(at -8.610092 35.999928 180)
			(size 0.450088 0.450088)
			(layers "F.Cu" "F.Mask" "F.Paste")
			(net "PVDDCR_CPU1_P1")
		)
		(pad "DH30" smd circle
			(at -7.670038 35.999928 180)
			(size 0.450088 0.450088)
			(layers "F.Cu" "F.Mask" "F.Paste")
			(net "Net_2075")
		)
		(pad "DH31" smd circle
			(at -6.729984 35.999928 180)
			(size 0.450088 0.450088)
			(layers "F.Cu" "F.Mask" "F.Paste")
			(net "PVDDCR_CPU1_P1")
		)
		(pad "DH32" smd circle
			(at -5.78993 35.999928 180)
			(size 0.450088 0.450088)
			(layers "F.Cu" "F.Mask" "F.Paste")
			(net "PVDDCR_CPU1_P1")
		)
		(pad "DH33" smd circle
			(at -4.849876 35.999928 180)
			(size 0.450088 0.450088)
			(layers "F.Cu" "F.Mask" "F.Paste")
			(net "TP_CPU1_UART1_RX")
		)
		(pad "DH34" smd circle
			(at -3.910076 35.999928 180)
			(size 0.450088 0.450088)
			(layers "F.Cu" "F.Mask" "F.Paste")
			(net "PVDDCR_CPU1_P1")
		)
		(pad "DH35" smd circle
			(at -2.970022 35.999928 180)
			(size 0.450088 0.450088)
			(layers "F.Cu" "F.Mask" "F.Paste")
			(net "PVDDCR_CPU1_P1")
		)
		(pad "DH36" smd circle
			(at -2.029968 35.999928 180)
			(size 0.450088 0.450088)
			(layers "F.Cu" "F.Mask" "F.Paste")
			(net "CPU1_PWRGD_OUT")
		)
		(pad "DH37" smd circle
			(at -1.089914 35.999928 180)
			(size 0.450088 0.450088)
			(layers "F.Cu" "F.Mask" "F.Paste")
			(net "GND")
		)
		(pad "DH39" smd circle
			(at 0.78994 35.999928 180)
			(size 0.450088 0.450088)
			(layers "F.Cu" "F.Mask" "F.Paste")
			(net "GND")
		)
		(pad "DH40" smd circle
			(at 1.729994 35.999928 180)
			(size 0.450088 0.450088)
			(layers "F.Cu" "F.Mask" "F.Paste")
			(net "NC_CPU1_USB11_OC_N")
		)
		(pad "DH41" smd circle
			(at 2.670048 35.999928 180)
			(size 0.450088 0.450088)
			(layers "F.Cu" "F.Mask" "F.Paste")
			(net "PVDDCR_CPU1_P1")
		)
		(pad "DH42" smd circle
			(at 3.610102 35.999928 180)
			(size 0.450088 0.450088)
			(layers "F.Cu" "F.Mask" "F.Paste")
			(net "PVDDCR_CPU1_P1")
		)
		(pad "DH43" smd circle
			(at 4.549902 35.999928 180)
			(size 0.450088 0.450088)
			(layers "F.Cu" "F.Mask" "F.Paste")
			(net "GND")
		)
		(pad "DH44" smd circle
			(at 5.489956 35.999928 180)
			(size 0.450088 0.450088)
			(layers "F.Cu" "F.Mask" "F.Paste")
			(net "PVDDCR_CPU1_P1")
		)
		(pad "DH45" smd circle
			(at 6.43001 35.999928 180)
			(size 0.450088 0.450088)
			(layers "F.Cu" "F.Mask" "F.Paste")
			(net "PVDDCR_CPU1_P1")
		)
		(pad "DH46" smd circle
			(at 7.370064 35.999928 180)
			(size 0.450088 0.450088)
			(layers "F.Cu" "F.Mask" "F.Paste")
			(net "GND")
		)
		(pad "DH47" smd circle
			(at 8.310118 35.999928 180)
			(size 0.450088 0.450088)
			(layers "F.Cu" "F.Mask" "F.Paste")
			(net "PVDDCR_CPU1_P1")
		)
		(pad "DH48" smd circle
			(at 9.249918 35.999928 180)
			(size 0.450088 0.450088)
			(layers "F.Cu" "F.Mask" "F.Paste")
			(net "PVDDCR_CPU1_P1")
		)
		(pad "DH49" smd circle
			(at 10.189972 35.999928 180)
			(size 0.450088 0.450088)
			(layers "F.Cu" "F.Mask" "F.Paste")
			(net "GND")
		)
		(pad "DH50" smd circle
			(at 11.130026 35.999928 180)
			(size 0.450088 0.450088)
			(layers "F.Cu" "F.Mask" "F.Paste")
			(net "PVDDCR_CPU1_P1")
		)
		(pad "DH51" smd circle
			(at 12.07008 35.999928 180)
			(size 0.450088 0.450088)
			(layers "F.Cu" "F.Mask" "F.Paste")
			(net "PVDDCR_CPU1_P1")
		)
		(pad "DH52" smd circle
			(at 13.00988 35.999928 180)
			(size 0.450088 0.450088)
			(layers "F.Cu" "F.Mask" "F.Paste")
			(net "GND")
		)
		(pad "DH53" smd circle
			(at 13.949934 35.999928 180)
			(size 0.450088 0.450088)
			(layers "F.Cu" "F.Mask" "F.Paste")
			(net "PVDDCR_CPU1_P1")
		)
		(pad "DH54" smd circle
			(at 14.889988 35.999928 180)
			(size 0.450088 0.450088)
			(layers "F.Cu" "F.Mask" "F.Paste")
			(net "PVDDCR_CPU1_P1")
		)
		(pad "DH55" smd circle
			(at 15.830042 35.999928 180)
			(size 0.450088 0.450088)
			(layers "F.Cu" "F.Mask" "F.Paste")
			(net "GND")
		)
		(pad "DH56" smd circle
			(at 16.770096 35.999928 180)
			(size 0.450088 0.450088)
			(layers "F.Cu" "F.Mask" "F.Paste")
			(net "PVDDCR_CPU1_P1")
		)
		(pad "DH57" smd circle
			(at 17.709896 35.999928 180)
			(size 0.450088 0.450088)
			(layers "F.Cu" "F.Mask" "F.Paste")
			(net "PVDDCR_CPU1_P1")
		)
		(pad "DH58" smd circle
			(at 18.64995 35.999928 180)
			(size 0.450088 0.450088)
			(layers "F.Cu" "F.Mask" "F.Paste")
			(net "NC_CPU1_USB3_USB11_TXN")
		)
		(pad "DH59" smd circle
			(at 19.590004 35.999928 180)
			(size 0.450088 0.450088)
			(layers "F.Cu" "F.Mask" "F.Paste")
			(net "GND")
		)
		(pad "DH60" smd circle
			(at 20.530058 35.999928 180)
			(size 0.450088 0.450088)
			(layers "F.Cu" "F.Mask" "F.Paste")
			(net "NC_CPU1_USB2_USB11_DP")
		)
		(pad "DH61" smd circle
			(at 21.470112 35.999928 180)
			(size 0.450088 0.450088)
			(layers "F.Cu" "F.Mask" "F.Paste")
			(net "GND")
		)
		(pad "DH62" smd circle
			(at 22.409912 35.999928 180)
			(size 0.450088 0.450088)
			(layers "F.Cu" "F.Mask" "F.Paste")
			(net "NC_CPU1_USB3_USB11_RXN")
		)
		(pad "DH63" smd circle
			(at 23.349966 35.999928 180)
			(size 0.450088 0.450088)
			(layers "F.Cu" "F.Mask" "F.Paste")
			(net "GND")
		)
		(pad "DH64" smd circle
			(at 24.29002 35.999928 180)
			(size 0.450088 0.450088)
			(layers "F.Cu" "F.Mask" "F.Paste")
			(net "GND")
		)
		(pad "DH65" smd circle
			(at 25.230074 35.999928 180)
			(size 0.450088 0.450088)
			(layers "F.Cu" "F.Mask" "F.Paste")
			(net "NC_CPU1_USB3_USB10_RXN")
		)
		(pad "DH66" smd circle
			(at 26.170128 35.999928 180)
			(size 0.450088 0.450088)
			(layers "F.Cu" "F.Mask" "F.Paste")
			(net "GND")
		)
		(pad "DH67" smd circle
			(at 27.109928 35.999928 180)
			(size 0.450088 0.450088)
			(layers "F.Cu" "F.Mask" "F.Paste")
			(net "NC_CPU1_USB2_USB10_DN")
		)
		(pad "DH68" smd circle
			(at 28.049982 35.999928 180)
			(size 0.450088 0.450088)
			(layers "F.Cu" "F.Mask" "F.Paste")
			(net "GND")
		)
		(pad "DH69" smd circle
			(at 28.990036 35.999928 180)
			(size 0.450088 0.450088)
			(layers "F.Cu" "F.Mask" "F.Paste")
			(net "NC_CPU1_USB3_USB10_TXP")
		)
		(pad "DH70" smd circle
			(at 29.93009 35.999928 180)
			(size 0.450088 0.450088)
			(layers "F.Cu" "F.Mask" "F.Paste")
			(net "GND")
		)
		(pad "DH71" smd circle
			(at 30.86989 35.999928 180)
			(size 0.450088 0.450088)
			(layers "F.Cu" "F.Mask" "F.Paste")
			(net "SMB_APML_CPU1_SDA")
		)
		(pad "DH72" smd circle
			(at 31.809944 35.999928 180)
			(size 0.450088 0.450088)
			(layers "F.Cu" "F.Mask" "F.Paste")
			(net "SVID_PVDDCR_CPU1_P1_SVD")
		)
		(pad "DH73" smd circle
			(at 32.749998 35.999928 180)
			(size 0.450088 0.450088)
			(layers "F.Cu" "F.Mask" "F.Paste")
			(net "CPU1_SP5R3")
		)
		(pad "DJ3" smd circle
			(at -32.580072 36.809934 180)
			(size 0.450088 0.450088)
			(layers "F.Cu" "F.Mask" "F.Paste")
			(net "VSENSE_VSS_SENSE_C_P1")
		)
		(pad "DJ4" smd circle
			(at -31.640018 36.809934 180)
			(size 0.450088 0.450088)
			(layers "F.Cu" "F.Mask" "F.Paste")
			(net "Net_2166")
		)
		(pad "DJ5" smd circle
			(at -30.699964 36.809934 180)
			(size 0.450088 0.450088)
			(layers "F.Cu" "F.Mask" "F.Paste")
			(net "CPU1_SLP_S3_N")
		)
		(pad "DJ7" smd circle
			(at -28.82011 36.809934 180)
			(size 0.450088 0.450088)
			(layers "F.Cu" "F.Mask" "F.Paste")
			(net "GND")
		)
		(pad "DJ8" smd circle
			(at -27.880056 36.809934 180)
			(size 0.450088 0.450088)
			(layers "F.Cu" "F.Mask" "F.Paste")
			(net "CPU1_PWR_GD_IN")
		)
		(pad "DJ9" smd circle
			(at -26.940002 36.809934 180)
			(size 0.450088 0.450088)
			(layers "F.Cu" "F.Mask" "F.Paste")
			(net "CPU1_THERMTRIP_N")
		)
	)
)
